# S9S_MB_2U (Grand Teton) — schematic netlist excerpt (pin names and nets, part order shuffled) for the footprints in the layout excerpt that follows; sources: Cadence DE-HDL packaged netlist, KiCad conversion of 03242023_DA0F0TMBIJ0_F0T_Motherboard_J_brd_V01_OCP.brd

R3432  Q_RES  4.7K 5% CHIP  pkg 0402LF  page 147 : A = P3V3_AUX ; B = GPU_FPGA_THERM_OVERT

(kicad_pcb
	(version 20260206)
	(generator "pcbnew")
	(generator_version "10.0")
	(general
		(thickness 1.6)
		(legacy_teardrops no)
	)
	(paper "A4")
	(title_block
		(title "03242023_DA0F0TMBIJ0_F0T_Motherboard_J_brd_V01_OCP.brd")
		(comment 1 "Grand Teton / footprints 3797-3797 of 6105")
	)
	(layers
		(0 "F.Cu" signal "TOP")
		(4 "In1.Cu" signal "GND")
		(6 "In2.Cu" signal "IN1")
		(8 "In3.Cu" signal "GND1")
		(10 "In4.Cu" signal "IN2")
		(12 "In5.Cu" signal "GND2")
		(14 "In6.Cu" signal "IN3")
		(16 "In7.Cu" signal "GND3")
		(18 "In8.Cu" signal "VCC")
		(20 "In9.Cu" signal "VCC1")
		(22 "In10.Cu" signal "GND4")
		(24 "In11.Cu" signal "IN4")
		(26 "In12.Cu" signal "GND5")
		(28 "In13.Cu" signal "IN5")
		(30 "In14.Cu" signal "GND6")
		(32 "In15.Cu" signal "IN6")
		(34 "In16.Cu" signal "GND7")
		(2 "B.Cu" signal "BOTTOM")
		(9 "F.Adhes" user "F.Adhesive")
		(11 "B.Adhes" user "B.Adhesive")
		(13 "F.Paste" user "Package Geometry/Pastemask Top")
		(15 "B.Paste" user "Package Geometry/Pastemask Bottom")
		(5 "F.SilkS" user "Ref Des/Silkscreen Top")
		(7 "B.SilkS" user "Ref Des/Silkscreen Bottom")
		(1 "F.Mask" user "Board Geometry/Soldermask Top")
		(3 "B.Mask" user "Board Geometry/Soldermask Bottom")
		(17 "Dwgs.User" user "User.Drawings")
		(19 "Cmts.User" user "User.Comments")
		(21 "Eco1.User" user "User.Eco1")
		(23 "Eco2.User" user "User.Eco2")
		(25 "Edge.Cuts" user "Board Geometry/Outline")
		(27 "Margin" user)
		(31 "F.CrtYd" user "Package Geometry/Place Bound Top")
		(29 "B.CrtYd" user "Package Geometry/Place Bound Bottom")
		(35 "F.Fab" user "Ref Des/Assembly Top")
		(33 "B.Fab" user "Ref Des/Assembly Bottom")
	)
	(footprint ""
		(layer "F.Cu")
		(at 31.962852 -407.509218 180)
		(property "Reference" "R3432"
			(at 0 0 180)
			(layer "F.SilkS")
			(hide yes)
			(effects
				(font
					(size 1.27 1.27)
				)
			)
		)
		(property "Value" ""
			(at 0 0 180)
			(layer "F.Fab")
			(effects
				(font
					(size 1.27 1.27)
				)
			)
		)
		(duplicate_pad_numbers_are_jumpers no)
		(fp_line
			(start 0.7874 0.4064)
			(end -0.7874 0.4064)
			(stroke
				(width 0.1524)
				(type default)
			)
			(layer "F.SilkS")
		)
		(fp_line
			(start 0.7874 -0.4064)
			(end 0.7874 0.4064)
			(stroke
				(width 0.1524)
				(type default)
			)
			(layer "F.SilkS")
		)
		(fp_line
			(start -0.7874 0.4064)
			(end -0.7874 -0.4064)
			(stroke
				(width 0.1524)
				(type default)
			)
			(layer "F.SilkS")
		)
		(fp_line
			(start -0.7874 -0.4064)
			(end 0.7874 -0.4064)
			(stroke
				(width 0.1524)
				(type default)
			)
			(layer "F.SilkS")
		)
		(fp_line
			(start 0.67945 0.3048)
			(end 0.120396 0.3048)
			(stroke
				(width 0.1)
				(type default)
			)
			(layer "F.Fab")
		)
		(fp_line
			(start 0.67945 -0.3048)
			(end 0.67945 0.3048)
			(stroke
				(width 0.1)
				(type default)
			)
			(layer "F.Fab")
		)
		(fp_line
			(start 0.12065 -0.2794)
			(end 0.12065 -0.3048)
			(stroke
				(width 0.1)
				(type default)
			)
			(layer "F.Fab")
		)
		(fp_line
			(start 0.12065 -0.3048)
			(end 0.67945 -0.3048)
			(stroke
				(width 0.1)
				(type default)
			)
			(layer "F.Fab")
		)
		(fp_line
			(start 0.120396 0.3048)
			(end 0.120396 0.2794)
			(stroke
				(width 0.1)
				(type default)
			)
			(layer "F.Fab")
		)
		(fp_line
			(start 0.120396 0.2794)
			(end -0.12065 0.2794)
			(stroke
				(width 0.1)
				(type default)
			)
			(layer "F.Fab")
		)
		(fp_line
			(start -0.12065 0.3048)
			(end -0.67945 0.3048)
			(stroke
				(width 0.1)
				(type default)
			)
			(layer "F.Fab")
		)
		(fp_line
			(start -0.12065 0.2794)
			(end -0.12065 0.3048)
			(stroke
				(width 0.1)
				(type default)
			)
			(layer "F.Fab")
		)
		(fp_line
			(start -0.12065 -0.2794)
			(end 0.12065 -0.2794)
			(stroke
				(width 0.1)
				(type default)
			)
			(layer "F.Fab")
		)
		(fp_line
			(start -0.12065 -0.305054)
			(end -0.12065 -0.2794)
			(stroke
				(width 0.1)
				(type default)
			)
			(layer "F.Fab")
		)
		(fp_line
			(start -0.67945 0.3048)
			(end -0.67945 -0.305054)
			(stroke
				(width 0.1)
				(type default)
			)
			(layer "F.Fab")
		)
		(fp_line
			(start -0.67945 -0.305054)
			(end -0.12065 -0.305054)
			(stroke
				(width 0.1)
				(type default)
			)
			(layer "F.Fab")
		)
		(pad "1" smd circle
			(at -0.40005 0 180)
			(size 0 0)
			(layers "F.Cu" "F.Mask" "F.Paste")
			(net "P3V3_AUX")
		)
		(pad "2" smd circle
			(at 0.40005 0 180)
			(size 0 0)
			(layers "F.Cu" "F.Mask" "F.Paste")
			(net "GPU_FPGA_THERM_OVERT")
		)
	)
)
